(kicad_pcb
	(version 20260206)
	(generator "pcbnew")
	(generator_version "10.0")
	(general
		(thickness 1.6)
		(legacy_teardrops no)
	)
	(paper "A4")
	(title_block
		(title "timecard-production-celestica-r4006 — R4006-B0001-02_R01.brd")
		(comment 1 "Time Appliance Project (Time Card) / footprints 762-766 of 1113")
	)
	(layers
		(0 "F.Cu" signal "TOP")
		(4 "In1.Cu" signal "L02_GND1")
		(6 "In2.Cu" signal "L03_SIG1")
		(8 "In3.Cu" signal "L04_GND2")
		(10 "In4.Cu" signal "L05_VCC1")
		(12 "In5.Cu" signal "L06_VCC2")
		(14 "In6.Cu" signal "L07_GND3")
		(16 "In7.Cu" signal "L08_SIG2")
		(18 "In8.Cu" signal "L09_GND4")
		(2 "B.Cu" signal "BOTTOM")
		(9 "F.Adhes" user "F.Adhesive")
		(11 "B.Adhes" user "B.Adhesive")
		(13 "F.Paste" user "Package Geometry/Pastemask Top")
		(15 "B.Paste" user "Package Geometry/Pastemask Bottom")
		(5 "F.SilkS" user "Ref Des/Silkscreen Top")
		(7 "B.SilkS" user "Ref Des/Silkscreen Bottom")
		(1 "F.Mask" user "Board Geometry/Soldermask Top")
		(3 "B.Mask" user "Board Geometry/Soldermask Bottom")
		(17 "Dwgs.User" user "User.Drawings")
		(19 "Cmts.User" user "User.Comments")
		(21 "Eco1.User" user "User.Eco1")
		(23 "Eco2.User" user "User.Eco2")
		(25 "Edge.Cuts" user "Board Geometry/Outline")
		(27 "Margin" user)
		(31 "F.CrtYd" user "Package Geometry/Place Bound Top")
		(29 "B.CrtYd" user "Package Geometry/Place Bound Bottom")
		(35 "F.Fab" user "Ref Des/Assembly Top")
		(33 "B.Fab" user "Ref Des/Assembly Bottom")
	)
	(footprint ""
		(layer "B.Cu")
		(at 60.784994 -15.367 -90)
		(property "Reference" "C23"
			(at 2.3368 -0.059436 270)
			(unlocked yes)
			(layer "B.SilkS")
			(effects
				(font
					(size 0.7874 0.5842)
					(thickness 0.1524)
				)
				(justify mirror)
			)
		)
		(property "Value" "VAL*"
			(at -0.0762 2.067306 270)
			(unlocked yes)
			(layer "B.Fab")
			(hide yes)
			(effects
				(font
					(size 0.7874 0.5842)
					(thickness 0.1524)
				)
				(justify mirror)
			)
		)
		(property "Tolerance" "TOL*"
			(at -0.0762 3.032506 270)
			(unlocked yes)
			(layer "Cmts.User")
			(hide yes)
			(effects
				(font
					(size 0.7874 0.5842)
					(thickness 0.1524)
				)
				(justify mirror)
			)
		)
		(property "User Part Number" "PARTNUM*"
			(at -0.1016 4.023106 270)
			(unlocked yes)
			(layer "Cmts.User")
			(hide yes)
			(effects
				(font
					(size 0.7874 0.5842)
					(thickness 0.1524)
				)
				(justify mirror)
			)
		)
		(property "Device Type" "CAPACITOR-G105-0B104-CK,0.1UF,A"
			(at -0.0508 1.127506 270)
			(unlocked yes)
			(layer "B.Fab")
			(hide yes)
			(effects
				(font
					(size 0.7874 0.5842)
					(thickness 0.1524)
				)
				(justify mirror)
			)
		)
		(duplicate_pad_numbers_are_jumpers no)
		(fp_line
			(start -1.143 0.5588)
			(end -1.143 -0.5588)
			(stroke
				(width 0.1)
				(type default)
			)
			(layer "B.SilkS")
		)
		(fp_line
			(start 1.143 0.5588)
			(end -1.143 0.5588)
			(stroke
				(width 0.1)
				(type default)
			)
			(layer "B.SilkS")
		)
		(fp_line
			(start -1.143 -0.5588)
			(end 1.143 -0.5588)
			(stroke
				(width 0.1)
				(type default)
			)
			(layer "B.SilkS")
		)
		(fp_line
			(start 1.143 -0.5588)
			(end 1.143 0.5588)
			(stroke
				(width 0.1)
				(type default)
			)
			(layer "B.SilkS")
		)
		(fp_rect
			(start 1.143 0.5588)
			(end -1.143 -0.5588)
			(stroke
				(width 0)
				(type default)
			)
			(fill no)
			(layer "B.CrtYd")
		)
		(fp_line
			(start -0.508 0.3048)
			(end -0.508 -0.3048)
			(stroke
				(width 0.1)
				(type default)
			)
			(layer "B.Fab")
		)
		(fp_line
			(start 0.508 0.3048)
			(end -0.508 0.3048)
			(stroke
				(width 0.1)
				(type default)
			)
			(layer "B.Fab")
		)
		(fp_line
			(start -0.508 -0.3048)
			(end 0.508 -0.3048)
			(stroke
				(width 0.1)
				(type default)
			)
			(layer "B.Fab")
		)
		(fp_line
			(start 0.508 -0.3048)
			(end 0.508 0.3048)
			(stroke
				(width 0.1)
				(type default)
			)
			(layer "B.Fab")
		)
		(pad "1" smd rect
			(at 0.5334 0 90)
			(size 0.7112 0.6096)
			(layers "B.Cu" "B.Mask" "B.Paste")
			(net "C_PCIEREFCLKN")
		)
		(pad "2" smd rect
			(at -0.5334 0 90)
			(size 0.7112 0.6096)
			(layers "B.Cu" "B.Mask" "B.Paste")
			(net "PCIE_REFCLKN")
		)
		(zone
			(layer "B.Cu")
			(hatch none 0.5)
			(connect_pads
				(clearance 0)
			)
			(min_thickness 0.25)
			(keepout
				(tracks allowed)
				(vias not_allowed)
				(pads allowed)
				(copperpour not_allowed)
				(footprints allowed)
			)
			(placement
				(enabled no)
				(sheetname "")
			)
			(fill
				(thermal_gap 0.5)
				(thermal_bridge_width 0.5)
				(island_removal_mode 0)
			)
			(polygon
				(pts
					(xy 60.480194 -15.2908) (xy 61.089794 -15.2908) (xy 61.089794 -15.4432) (xy 60.480194 -15.4432)
				)
			)
		)
	)
	(footprint ""
		(layer "B.Cu")
		(at 72.263 -55.753 90)
		(property "Reference" "FU3"
			(at -2.413 0.08763 270)
			(unlocked yes)
			(layer "B.SilkS")
			(effects
				(font
					(size 0.7874 0.5842)
					(thickness 0.1524)
				)
				(justify mirror)
			)
		)
		(property "Value" "VAL*"
			(at 0.0254 2.524506 90)
			(unlocked yes)
			(layer "B.Fab")
			(hide yes)
			(effects
				(font
					(size 0.7874 0.5842)
					(thickness 0.1524)
				)
				(justify mirror)
			)
		)
		(property "Tolerance" "TOL*"
			(at 0.0254 3.464306 90)
			(unlocked yes)
			(layer "Cmts.User")
			(hide yes)
			(effects
				(font
					(size 0.7874 0.5842)
					(thickness 0.1524)
				)
				(justify mirror)
			)
		)
		(property "User Part Number" "PARTNUM*"
			(at 0.0254 4.505706 90)
			(unlocked yes)
			(layer "Cmts.User")
			(hide yes)
			(effects
				(font
					(size 0.7874 0.5842)
					(thickness 0.1524)
				)
				(justify mirror)
			)
		)
		(property "Device Type" "FUSE-G280-10049-01,1A"
			(at 0 1.610106 90)
			(unlocked yes)
			(layer "B.Fab")
			(hide yes)
			(effects
				(font
					(size 0.7874 0.5842)
					(thickness 0.1524)
				)
				(justify mirror)
			)
		)
		(duplicate_pad_numbers_are_jumpers no)
		(fp_line
			(start 1.3208 -0.7112)
			(end -1.3208 -0.7112)
			(stroke
				(width 0.1)
				(type default)
			)
			(layer "B.SilkS")
		)
		(fp_line
			(start -1.3208 -0.7112)
			(end -1.3208 0.7112)
			(stroke
				(width 0.1)
				(type default)
			)
			(layer "B.SilkS")
		)
		(fp_line
			(start 1.3208 0.7112)
			(end 1.3208 -0.7112)
			(stroke
				(width 0.1)
				(type default)
			)
			(layer "B.SilkS")
		)
		(fp_line
			(start -1.3208 0.7112)
			(end 1.3208 0.7112)
			(stroke
				(width 0.1)
				(type default)
			)
			(layer "B.SilkS")
		)
		(fp_rect
			(start 1.3208 0.7112)
			(end -1.3208 -0.7112)
			(stroke
				(width 0)
				(type default)
			)
			(fill no)
			(layer "B.CrtYd")
		)
		(fp_line
			(start 0.8128 -0.4572)
			(end -0.8128 -0.4572)
			(stroke
				(width 0.1)
				(type default)
			)
			(layer "B.Fab")
		)
		(fp_line
			(start -0.8128 -0.4572)
			(end -0.8128 0.4572)
			(stroke
				(width 0.1)
				(type default)
			)
			(layer "B.Fab")
		)
		(fp_line
			(start 0.8128 0.4572)
			(end 0.8128 -0.4572)
			(stroke
				(width 0.1)
				(type default)
			)
			(layer "B.Fab")
		)
		(fp_line
			(start -0.8128 0.4572)
			(end 0.8128 0.4572)
			(stroke
				(width 0.1)
				(type default)
			)
			(layer "B.Fab")
		)
		(pad "1" smd rect
			(at 0.6858 0 270)
			(size 0.762 0.8636)
			(layers "B.Cu" "B.Mask" "B.Paste")
			(net "UNNAMED_527_FUSE_I244_1")
		)
		(pad "2" smd rect
			(at -0.6858 0 270)
			(size 0.762 0.8636)
			(layers "B.Cu" "B.Mask" "B.Paste")
			(net "XP5R0V_MAC_USB")
		)
		(zone
			(layer "B.Cu")
			(hatch none 0.5)
			(connect_pads
				(clearance 0)
			)
			(min_thickness 0.25)
			(keepout
				(tracks not_allowed)
				(vias allowed)
				(pads allowed)
				(copperpour not_allowed)
				(footprints allowed)
			)
			(placement
				(enabled no)
				(sheetname "")
			)
			(fill
				(thermal_gap 0.5)
				(thermal_bridge_width 0.5)
				(island_removal_mode 0)
			)
			(polygon
				(pts
					(xy 72.7202 -55.9054) (xy 71.8058 -55.9054) (xy 71.8058 -55.6006) (xy 72.7202 -55.6006)
				)
			)
		)
		(zone
			(layer "B.Cu")
			(hatch none 0.5)
			(connect_pads
				(clearance 0)
			)
			(min_thickness 0.25)
			(keepout
				(tracks allowed)
				(vias not_allowed)
				(pads allowed)
				(copperpour not_allowed)
				(footprints allowed)
			)
			(placement
				(enabled no)
				(sheetname "")
			)
			(fill
				(thermal_gap 0.5)
				(thermal_bridge_width 0.5)
				(island_removal_mode 0)
			)
			(polygon
				(pts
					(xy 72.7202 -55.9054) (xy 71.8058 -55.9054) (xy 71.8058 -55.6006) (xy 72.7202 -55.6006)
				)
			)
		)
	)
	(footprint ""
		(layer "B.Cu")
		(at 98.991166 -32.857694)
		(property "Reference" "C116"
			(at 2.989834 0.258064 0)
			(unlocked yes)
			(layer "B.SilkS")
			(effects
				(font
					(size 0.7874 0.5842)
					(thickness 0.1524)
				)
				(justify mirror)
			)
		)
		(property "Value" "VAL*"
			(at -0.0762 2.067306 0)
			(unlocked yes)
			(layer "B.Fab")
			(hide yes)
			(effects
				(font
					(size 0.7874 0.5842)
					(thickness 0.1524)
				)
				(justify mirror)
			)
		)
		(property "Tolerance" "TOL*"
			(at -0.0762 3.032506 0)
			(unlocked yes)
			(layer "Cmts.User")
			(hide yes)
			(effects
				(font
					(size 0.7874 0.5842)
					(thickness 0.1524)
				)
				(justify mirror)
			)
		)
		(property "User Part Number" "PARTNUM*"
			(at -0.1016 4.023106 0)
			(unlocked yes)
			(layer "Cmts.User")
			(hide yes)
			(effects
				(font
					(size 0.7874 0.5842)
					(thickness 0.1524)
				)
				(justify mirror)
			)
		)
		(property "Device Type" "CAPACITOR-G105-0B104-CK,0.1UF,A"
			(at -0.0508 1.127506 0)
			(unlocked yes)
			(layer "B.Fab")
			(hide yes)
			(effects
				(font
					(size 0.7874 0.5842)
					(thickness 0.1524)
				)
				(justify mirror)
			)
		)
		(duplicate_pad_numbers_are_jumpers no)
		(fp_line
			(start -1.143 -0.5588)
			(end 1.143 -0.5588)
			(stroke
				(width 0.1)
				(type default)
			)
			(layer "B.SilkS")
		)
		(fp_line
			(start -1.143 0.5588)
			(end -1.143 -0.5588)
			(stroke
				(width 0.1)
				(type default)
			)
			(layer "B.SilkS")
		)
		(fp_line
			(start 1.143 -0.5588)
			(end 1.143 0.5588)
			(stroke
				(width 0.1)
				(type default)
			)
			(layer "B.SilkS")
		)
		(fp_line
			(start 1.143 0.5588)
			(end -1.143 0.5588)
			(stroke
				(width 0.1)
				(type default)
			)
			(layer "B.SilkS")
		)
		(fp_poly
			(pts
				(xy 1.143 0.5588) (xy -1.143 0.5588) (xy -1.143 -0.5588) (xy 1.143 -0.5588)
			)
			(stroke
				(width 0)
				(type default)
			)
			(fill no)
			(layer "B.CrtYd")
		)
		(fp_line
			(start -0.508 -0.3048)
			(end 0.508 -0.3048)
			(stroke
				(width 0.1)
				(type default)
			)
			(layer "B.Fab")
		)
		(fp_line
			(start -0.508 0.3048)
			(end -0.508 -0.3048)
			(stroke
				(width 0.1)
				(type default)
			)
			(layer "B.Fab")
		)
		(fp_line
			(start 0.508 -0.3048)
			(end 0.508 0.3048)
			(stroke
				(width 0.1)
				(type default)
			)
			(layer "B.Fab")
		)
		(fp_line
			(start 0.508 0.3048)
			(end -0.508 0.3048)
			(stroke
				(width 0.1)
				(type default)
			)
			(layer "B.Fab")
		)
		(pad "1" smd rect
			(at 0.5334 0 180)
			(size 0.7112 0.6096)
			(layers "B.Cu" "B.Mask" "B.Paste")
			(net "XP2R5V_FPGA")
		)
		(pad "2" smd rect
			(at -0.5334 0 180)
			(size 0.7112 0.6096)
			(layers "B.Cu" "B.Mask" "B.Paste")
			(net "SG")
		)
		(zone
			(layer "B.Cu")
			(hatch none 0.5)
			(connect_pads
				(clearance 0)
			)
			(min_thickness 0.25)
			(keepout
				(tracks allowed)
				(vias not_allowed)
				(pads allowed)
				(copperpour not_allowed)
				(footprints allowed)
			)
			(placement
				(enabled no)
				(sheetname "")
			)
			(fill
				(thermal_gap 0.5)
				(thermal_bridge_width 0.5)
				(island_removal_mode 0)
			)
			(polygon
				(pts
					(xy 99.067366 -32.552894) (xy 99.067366 -33.162494) (xy 98.914966 -33.162494) (xy 98.914966 -32.552894)
				)
			)
		)
		(zone
			(layer "B.Cu")
			(hatch none 0.5)
			(connect_pads
				(clearance 0)
			)
			(min_thickness 0.25)
			(keepout
				(tracks not_allowed)
				(vias allowed)
				(pads allowed)
				(copperpour not_allowed)
				(footprints allowed)
			)
			(placement
				(enabled no)
				(sheetname "")
			)
			(fill
				(thermal_gap 0.5)
				(thermal_bridge_width 0.5)
				(island_removal_mode 0)
			)
			(polygon
				(pts
					(xy 99.067366 -32.552894) (xy 99.067366 -33.162494) (xy 98.914966 -33.162494) (xy 98.914966 -32.552894)
				)
			)
		)
	)
	(footprint ""
		(layer "B.Cu")
		(at 114.347244 -36.823142 180)
		(property "Reference" "R278"
			(at -0.079756 0.991108 0)
			(unlocked yes)
			(layer "B.SilkS")
			(effects
				(font
					(size 0.635 0.4064)
					(thickness 0.1524)
				)
				(justify mirror)
			)
		)
		(property "Value" "VAL*"
			(at 0 3.718306 180)
			(unlocked yes)
			(layer "B.Fab")
			(hide yes)
			(effects
				(font
					(size 0.7874 0.5842)
					(thickness 0.127)
				)
				(justify mirror)
			)
		)
		(property "Tolerance" "TOL*"
			(at 0 4.861306 180)
			(unlocked yes)
			(layer "Cmts.User")
			(hide yes)
			(effects
				(font
					(size 0.7874 0.5842)
					(thickness 0.127)
				)
				(justify mirror)
			)
		)
		(property "User Part Number" "PARTNUM*"
			(at 0 2.575306 180)
			(unlocked yes)
			(layer "Cmts.User")
			(hide yes)
			(effects
				(font
					(size 0.7874 0.5842)
					(thickness 0.127)
				)
				(justify mirror)
			)
		)
		(property "Device Type" "RESISTOR-G155-11000-01,100OHM,A"
			(at 0 1.432306 180)
			(unlocked yes)
			(layer "B.Fab")
			(hide yes)
			(effects
				(font
					(size 0.7874 0.5842)
					(thickness 0.127)
				)
				(justify mirror)
			)
		)
		(duplicate_pad_numbers_are_jumpers no)
		(fp_line
			(start 0.970026 0.4699)
			(end 0.970026 -0.4699)
			(stroke
				(width 0.1)
				(type default)
			)
			(layer "B.SilkS")
		)
		(fp_line
			(start 0.970026 -0.4699)
			(end -0.970026 -0.4699)
			(stroke
				(width 0.1)
				(type default)
			)
			(layer "B.SilkS")
		)
		(fp_line
			(start -0.970026 0.4699)
			(end 0.970026 0.4699)
			(stroke
				(width 0.1)
				(type default)
			)
			(layer "B.SilkS")
		)
		(fp_line
			(start -0.970026 -0.4699)
			(end -0.970026 0.4699)
			(stroke
				(width 0.1)
				(type default)
			)
			(layer "B.SilkS")
		)
		(fp_poly
			(pts
				(xy 0.970026 0.4699) (xy -0.970026 0.4699) (xy -0.970026 -0.4699) (xy 0.970026 -0.4699)
			)
			(stroke
				(width 0)
				(type default)
			)
			(fill no)
			(layer "B.CrtYd")
		)
		(fp_line
			(start 0.508 0.3048)
			(end 0.508 -0.3048)
			(stroke
				(width 0.1)
				(type default)
			)
			(layer "B.Fab")
		)
		(fp_line
			(start 0.508 -0.3048)
			(end -0.508 -0.3048)
			(stroke
				(width 0.1)
				(type default)
			)
			(layer "B.Fab")
		)
		(fp_line
			(start -0.508 0.3048)
			(end 0.508 0.3048)
			(stroke
				(width 0.1)
				(type default)
			)
			(layer "B.Fab")
		)
		(fp_line
			(start -0.508 -0.3048)
			(end -0.508 0.3048)
			(stroke
				(width 0.1)
				(type default)
			)
			(layer "B.Fab")
		)
		(pad "1" smd circle
			(at 0.500126 0)
			(size 0.635 0.635)
			(layers "B.Cu" "B.Mask" "B.Paste")
			(net "MHZ200CLKP_CLKIN")
		)
		(pad "2" smd circle
			(at -0.500126 0)
			(size 0.635 0.635)
			(layers "B.Cu" "B.Mask" "B.Paste")
			(net "MHZ200CLKN_CLKIN")
		)
	)
	(footprint ""
		(layer "B.Cu")
		(at 78.994 -73.152 -90)
		(property "Reference" "C283"
			(at -3.683 0.42037 270)
			(unlocked yes)
			(layer "B.SilkS")
			(effects
				(font
					(size 0.7874 0.5842)
					(thickness 0.1524)
				)
				(justify mirror)
			)
		)
		(property "Value" "VAL*"
			(at -0.0762 3.134106 270)
			(unlocked yes)
			(layer "B.Fab")
			(hide yes)
			(effects
				(font
					(size 0.7874 0.5842)
					(thickness 0.1524)
				)
				(justify mirror)
			)
		)
		(property "Device Type" "CAPACITOR-G107-0F106-EM,10UF,2A"
			(at -0.0508 2.194306 270)
			(unlocked yes)
			(layer "B.Fab")
			(hide yes)
			(effects
				(font
					(size 0.7874 0.5842)
					(thickness 0.1524)
				)
				(justify mirror)
			)
		)
		(property "User Part Number" "PARTNUM*"
			(at -0.1016 5.013706 270)
			(unlocked yes)
			(layer "Cmts.User")
			(hide yes)
			(effects
				(font
					(size 0.7874 0.5842)
					(thickness 0.1524)
				)
				(justify mirror)
			)
		)
		(property "Tolerance" "TOL*"
			(at -0.0762 4.048506 270)
			(unlocked yes)
			(layer "Cmts.User")
			(hide yes)
			(effects
				(font
					(size 0.7874 0.5842)
					(thickness 0.1524)
				)
				(justify mirror)
			)
		)
		(duplicate_pad_numbers_are_jumpers no)
		(fp_line
			(start -1.5748 0.9398)
			(end -1.5748 -0.9398)
			(stroke
				(width 0.1)
				(type default)
			)
			(layer "B.SilkS")
		)
		(fp_line
			(start 1.5748 0.9398)
			(end -1.5748 0.9398)
			(stroke
				(width 0.1)
				(type default)
			)
			(layer "B.SilkS")
		)
		(fp_line
			(start -1.5748 -0.9398)
			(end 1.5748 -0.9398)
			(stroke
				(width 0.1)
				(type default)
			)
			(layer "B.SilkS")
		)
		(fp_line
			(start 1.5748 -0.9398)
			(end 1.5748 0.9398)
			(stroke
				(width 0.1)
				(type default)
			)
			(layer "B.SilkS")
		)
		(fp_rect
			(start 1.5748 0.9398)
			(end -1.5748 -0.9398)
			(stroke
				(width 0)
				(type default)
			)
			(fill no)
			(layer "B.CrtYd")
		)
		(fp_line
			(start -1.016 0.635)
			(end -1.016 -0.635)
			(stroke
				(width 0.1)
				(type default)
			)
			(layer "B.Fab")
		)
		(fp_line
			(start 1.016 0.635)
			(end -1.016 0.635)
			(stroke
				(width 0.1)
				(type default)
			)
			(layer "B.Fab")
		)
		(fp_line
			(start -1.016 -0.635)
			(end 1.016 -0.635)
			(stroke
				(width 0.1)
				(type default)
			)
			(layer "B.Fab")
		)
		(fp_line
			(start 1.016 -0.635)
			(end 1.016 0.635)
			(stroke
				(width 0.1)
				(type default)
			)
			(layer "B.Fab")
		)
		(pad "1" smd rect
			(at 0.8382 0 90)
			(size 0.9652 1.3716)
			(layers "B.Cu" "B.Mask" "B.Paste")
			(net "XP5R0V_MAC")
		)
		(pad "2" smd rect
			(at -0.8382 0 90)
			(size 0.9652 1.3716)
			(layers "B.Cu" "B.Mask" "B.Paste")
			(net "SG")
		)
		(zone
			(layer "B.Cu")
			(hatch none 0.5)
			(connect_pads
				(clearance 0)
			)
			(min_thickness 0.25)
			(keepout
				(tracks allowed)
				(vias not_allowed)
				(pads allowed)
				(copperpour not_allowed)
				(footprints allowed)
			)
			(placement
				(enabled no)
				(sheetname "")
			)
			(fill
				(thermal_gap 0.5)
				(thermal_bridge_width 0.5)
				(island_removal_mode 0)
			)
			(polygon
				(pts
					(xy 78.359 -72.9234) (xy 79.629 -72.9234) (xy 79.629 -73.3806) (xy 78.359 -73.3806)
				)
			)
		)
	)
)
